(kicad_pcb
	(version 20260206)
	(generator "pcbnew")
	(generator_version "10.0")
	(general
		(thickness 1.6)
		(legacy_teardrops no)
	)
	(paper "A4")
	(title_block
		(title "04192023_DAF0TMB3IC0_F0TG_MB_C_brd_V02_OCP.brd")
		(comment 1 "Grand Teton / footprints 3658-3663 of 8354")
	)
	(layers
		(0 "F.Cu" signal "TOP")
		(4 "In1.Cu" signal "GND")
		(6 "In2.Cu" signal "IN1")
		(8 "In3.Cu" signal "GND1")
		(10 "In4.Cu" signal "IN2")
		(12 "In5.Cu" signal "GND2")
		(14 "In6.Cu" signal "IN3")
		(16 "In7.Cu" signal "GND3")
		(18 "In8.Cu" signal "VCC")
		(20 "In9.Cu" signal "VCC1")
		(22 "In10.Cu" signal "GND4")
		(24 "In11.Cu" signal "IN4")
		(26 "In12.Cu" signal "GND5")
		(28 "In13.Cu" signal "IN5")
		(30 "In14.Cu" signal "GND6")
		(32 "In15.Cu" signal "IN6")
		(34 "In16.Cu" signal "GND7")
		(2 "B.Cu" signal "BOTTOM")
		(9 "F.Adhes" user "F.Adhesive")
		(11 "B.Adhes" user "B.Adhesive")
		(13 "F.Paste" user "Package Geometry/Pastemask Top")
		(15 "B.Paste" user "Package Geometry/Pastemask Bottom")
		(5 "F.SilkS" user "Ref Des/Silkscreen Top")
		(7 "B.SilkS" user "Ref Des/Silkscreen Bottom")
		(1 "F.Mask" user "Board Geometry/Soldermask Top")
		(3 "B.Mask" user "Board Geometry/Soldermask Bottom")
		(17 "Dwgs.User" user "User.Drawings")
		(19 "Cmts.User" user "User.Comments")
		(21 "Eco1.User" user "User.Eco1")
		(23 "Eco2.User" user "User.Eco2")
		(25 "Edge.Cuts" user "Board Geometry/Outline")
		(27 "Margin" user)
		(31 "F.CrtYd" user "Package Geometry/Place Bound Top")
		(29 "B.CrtYd" user "Package Geometry/Place Bound Bottom")
		(35 "F.Fab" user "Ref Des/Assembly Top")
		(33 "B.Fab" user "Ref Des/Assembly Bottom")
	)
	(footprint ""
		(layer "F.Cu")
		(at 94.605602 -41.445942 180)
		(property "Reference" "R3185"
			(at 0 0 180)
			(layer "F.SilkS")
			(hide yes)
			(effects
				(font
					(size 1.27 1.27)
				)
			)
		)
		(property "Value" ""
			(at 0 0 180)
			(layer "F.Fab")
			(effects
				(font
					(size 1.27 1.27)
				)
			)
		)
		(duplicate_pad_numbers_are_jumpers no)
		(fp_line
			(start 0.7874 0.4064)
			(end -0.7874 0.4064)
			(stroke
				(width 0.1524)
				(type default)
			)
			(layer "F.SilkS")
		)
		(fp_line
			(start 0.7874 -0.4064)
			(end 0.7874 0.4064)
			(stroke
				(width 0.1524)
				(type default)
			)
			(layer "F.SilkS")
		)
		(fp_line
			(start -0.7874 0.4064)
			(end -0.7874 -0.4064)
			(stroke
				(width 0.1524)
				(type default)
			)
			(layer "F.SilkS")
		)
		(fp_line
			(start -0.7874 -0.4064)
			(end 0.7874 -0.4064)
			(stroke
				(width 0.1524)
				(type default)
			)
			(layer "F.SilkS")
		)
		(fp_line
			(start 0.67945 0.3048)
			(end 0.120396 0.3048)
			(stroke
				(width 0.1)
				(type default)
			)
			(layer "F.Fab")
		)
		(fp_line
			(start 0.67945 -0.3048)
			(end 0.67945 0.3048)
			(stroke
				(width 0.1)
				(type default)
			)
			(layer "F.Fab")
		)
		(fp_line
			(start 0.12065 -0.2794)
			(end 0.12065 -0.3048)
			(stroke
				(width 0.1)
				(type default)
			)
			(layer "F.Fab")
		)
		(fp_line
			(start 0.12065 -0.3048)
			(end 0.67945 -0.3048)
			(stroke
				(width 0.1)
				(type default)
			)
			(layer "F.Fab")
		)
		(fp_line
			(start 0.120396 0.3048)
			(end 0.120396 0.2794)
			(stroke
				(width 0.1)
				(type default)
			)
			(layer "F.Fab")
		)
		(fp_line
			(start 0.120396 0.2794)
			(end -0.12065 0.2794)
			(stroke
				(width 0.1)
				(type default)
			)
			(layer "F.Fab")
		)
		(fp_line
			(start -0.12065 0.3048)
			(end -0.67945 0.3048)
			(stroke
				(width 0.1)
				(type default)
			)
			(layer "F.Fab")
		)
		(fp_line
			(start -0.12065 0.2794)
			(end -0.12065 0.3048)
			(stroke
				(width 0.1)
				(type default)
			)
			(layer "F.Fab")
		)
		(fp_line
			(start -0.12065 -0.2794)
			(end 0.12065 -0.2794)
			(stroke
				(width 0.1)
				(type default)
			)
			(layer "F.Fab")
		)
		(fp_line
			(start -0.12065 -0.305054)
			(end -0.12065 -0.2794)
			(stroke
				(width 0.1)
				(type default)
			)
			(layer "F.Fab")
		)
		(fp_line
			(start -0.67945 0.3048)
			(end -0.67945 -0.305054)
			(stroke
				(width 0.1)
				(type default)
			)
			(layer "F.Fab")
		)
		(fp_line
			(start -0.67945 -0.305054)
			(end -0.12065 -0.305054)
			(stroke
				(width 0.1)
				(type default)
			)
			(layer "F.Fab")
		)
		(pad "1" smd circle
			(at -0.40005 0 180)
			(size 0 0)
			(layers "F.Cu" "F.Mask" "F.Paste")
			(net "OCP_V3_2_WAKE_BUFF_N")
		)
		(pad "2" smd circle
			(at 0.40005 0 180)
			(size 0 0)
			(layers "F.Cu" "F.Mask" "F.Paste")
			(net "OCP_V3_2_WAKE_BUFF_R_N")
		)
	)
	(footprint ""
		(layer "F.Cu")
		(at 108.092748 -187.492894 180)
		(property "Reference" "PL32"
			(at -0.856488 6.245098 0)
			(unlocked yes)
			(layer "F.SilkS")
			(effects
				(font
					(size 0.7874 0.5842)
					(thickness 0.1524)
				)
				(justify left)
			)
		)
		(property "Value" ""
			(at 0 0 180)
			(layer "F.Fab")
			(effects
				(font
					(size 1.27 1.27)
				)
			)
		)
		(duplicate_pad_numbers_are_jumpers no)
		(fp_line
			(start 3.750056 5.500116)
			(end 3.750056 -5.500116)
			(stroke
				(width 0.1524)
				(type default)
			)
			(layer "F.SilkS")
		)
		(fp_line
			(start 3.750056 -5.500116)
			(end 2.393442 -5.500116)
			(stroke
				(width 0.1524)
				(type default)
			)
			(layer "F.SilkS")
		)
		(fp_line
			(start 2.393442 5.500116)
			(end 3.750056 5.500116)
			(stroke
				(width 0.1524)
				(type default)
			)
			(layer "F.SilkS")
		)
		(fp_line
			(start -2.393442 5.500116)
			(end -3.750056 5.500116)
			(stroke
				(width 0.1524)
				(type default)
			)
			(layer "F.SilkS")
		)
		(fp_line
			(start -3.750056 5.500116)
			(end -3.750056 -5.500116)
			(stroke
				(width 0.1524)
				(type default)
			)
			(layer "F.SilkS")
		)
		(fp_line
			(start -3.750056 -5.500116)
			(end -2.393442 -5.500116)
			(stroke
				(width 0.1524)
				(type default)
			)
			(layer "F.SilkS")
		)
		(fp_poly
			(pts
				(xy 3.963416 -4.623562) (xy 4.741418 -5.01269) (xy 4.741418 -4.234434)
			)
			(stroke
				(width 0)
				(type default)
			)
			(fill yes)
			(layer "F.SilkS")
		)
		(fp_line
			(start 3.750056 5.500116)
			(end 3.750056 -5.500116)
			(stroke
				(width 0.1)
				(type default)
			)
			(layer "F.Fab")
		)
		(fp_line
			(start 3.750056 -5.500116)
			(end -3.750056 -5.500116)
			(stroke
				(width 0.1)
				(type default)
			)
			(layer "F.Fab")
		)
		(fp_line
			(start -3.750056 5.500116)
			(end 3.750056 5.500116)
			(stroke
				(width 0.1)
				(type default)
			)
			(layer "F.Fab")
		)
		(fp_line
			(start -3.750056 -5.500116)
			(end -3.750056 5.500116)
			(stroke
				(width 0.1)
				(type default)
			)
			(layer "F.Fab")
		)
		(fp_poly
			(pts
				(xy -4.9276 -4.757928) (xy -4.9276 -3.741928) (xy -3.9116 -4.249928)
			)
			(stroke
				(width 0)
				(type default)
			)
			(fill yes)
			(layer "F.Fab")
		)
		(pad "1" smd rect
			(at 0 -4.249928 90)
			(size 2.413 4.5212)
			(layers "F.Cu" "F.Mask" "F.Paste")
			(net "SW_PVDDCR_CPU0_P1_SW4")
		)
		(pad "2" smd rect
			(at 0 -1.175004 90)
			(size 1.3716 4.5212)
			(layers "F.Cu" "F.Mask" "F.Paste")
			(net "IND_CPU0_P1_CPL3")
		)
		(pad "3" smd rect
			(at 0 1.175004 90)
			(size 1.3716 4.5212)
			(layers "F.Cu" "F.Mask" "F.Paste")
			(net "GND")
		)
		(pad "4" smd rect
			(at 0 4.249928 90)
			(size 2.413 4.5212)
			(layers "F.Cu" "F.Mask" "F.Paste")
			(net "PVDDCR_CPU0_P1")
		)
	)
	(footprint ""
		(layer "F.Cu")
		(at 321.112896 -378.95403 -90)
		(property "Reference" "C909"
			(at 0 0 270)
			(layer "F.SilkS")
			(hide yes)
			(effects
				(font
					(size 1.27 1.27)
				)
			)
		)
		(property "Value" ""
			(at 0 0 270)
			(layer "F.Fab")
			(effects
				(font
					(size 1.27 1.27)
				)
			)
		)
		(duplicate_pad_numbers_are_jumpers no)
		(fp_line
			(start -0.299974 0.150114)
			(end -0.299974 -0.150114)
			(stroke
				(width 0.1)
				(type default)
			)
			(layer "F.Fab")
		)
		(fp_line
			(start 0.299974 0.150114)
			(end -0.299974 0.150114)
			(stroke
				(width 0.1)
				(type default)
			)
			(layer "F.Fab")
		)
		(fp_line
			(start -0.299974 -0.150114)
			(end 0.299974 -0.150114)
			(stroke
				(width 0.1)
				(type default)
			)
			(layer "F.Fab")
		)
		(fp_line
			(start 0.299974 -0.150114)
			(end 0.299974 0.150114)
			(stroke
				(width 0.1)
				(type default)
			)
			(layer "F.Fab")
		)
		(pad "1" smd rect
			(at -0.2667 0 270)
			(size 0.3048 0.381)
			(layers "F.Cu" "F.Mask" "F.Paste")
			(net "P5E_CPU0_P0_TX_C_DP<12>")
		)
		(pad "2" smd rect
			(at 0.2667 0 270)
			(size 0.3048 0.381)
			(layers "F.Cu" "F.Mask" "F.Paste")
			(net "P5E_CPU0_P0_TX_DP<12>")
		)
	)
	(footprint ""
		(layer "F.Cu")
		(at 66.726054 -334.998314 -90)
		(property "Reference" "PC402_C1P1_3"
			(at 0 0 270)
			(layer "F.SilkS")
			(hide yes)
			(effects
				(font
					(size 1.27 1.27)
				)
			)
		)
		(property "Value" ""
			(at 0 0 270)
			(layer "F.Fab")
			(effects
				(font
					(size 1.27 1.27)
				)
			)
		)
		(duplicate_pad_numbers_are_jumpers no)
		(fp_line
			(start -0.7874 0.4064)
			(end -0.7874 -0.4064)
			(stroke
				(width 0.1524)
				(type default)
			)
			(layer "F.SilkS")
		)
		(fp_line
			(start 0.7874 0.4064)
			(end -0.7874 0.4064)
			(stroke
				(width 0.1524)
				(type default)
			)
			(layer "F.SilkS")
		)
		(fp_line
			(start -0.7874 -0.4064)
			(end 0.7874 -0.4064)
			(stroke
				(width 0.1524)
				(type default)
			)
			(layer "F.SilkS")
		)
		(fp_line
			(start 0.7874 -0.4064)
			(end 0.7874 0.4064)
			(stroke
				(width 0.1524)
				(type default)
			)
			(layer "F.SilkS")
		)
		(fp_line
			(start -0.67945 0.3048)
			(end -0.67945 -0.305054)
			(stroke
				(width 0.1)
				(type default)
			)
			(layer "F.Fab")
		)
		(fp_line
			(start -0.12065 0.3048)
			(end -0.67945 0.3048)
			(stroke
				(width 0.1)
				(type default)
			)
			(layer "F.Fab")
		)
		(fp_line
			(start 0.120396 0.3048)
			(end 0.120396 0.2794)
			(stroke
				(width 0.1)
				(type default)
			)
			(layer "F.Fab")
		)
		(fp_line
			(start 0.67945 0.3048)
			(end 0.120396 0.3048)
			(stroke
				(width 0.1)
				(type default)
			)
			(layer "F.Fab")
		)
		(fp_line
			(start -0.12065 0.2794)
			(end -0.12065 0.3048)
			(stroke
				(width 0.1)
				(type default)
			)
			(layer "F.Fab")
		)
		(fp_line
			(start 0.120396 0.2794)
			(end -0.12065 0.2794)
			(stroke
				(width 0.1)
				(type default)
			)
			(layer "F.Fab")
		)
		(fp_line
			(start -0.12065 -0.2794)
			(end 0.12065 -0.2794)
			(stroke
				(width 0.1)
				(type default)
			)
			(layer "F.Fab")
		)
		(fp_line
			(start 0.12065 -0.2794)
			(end 0.12065 -0.3048)
			(stroke
				(width 0.1)
				(type default)
			)
			(layer "F.Fab")
		)
		(fp_line
			(start 0.12065 -0.3048)
			(end 0.67945 -0.3048)
			(stroke
				(width 0.1)
				(type default)
			)
			(layer "F.Fab")
		)
		(fp_line
			(start 0.67945 -0.3048)
			(end 0.67945 0.3048)
			(stroke
				(width 0.1)
				(type default)
			)
			(layer "F.Fab")
		)
		(fp_line
			(start -0.67945 -0.305054)
			(end -0.12065 -0.305054)
			(stroke
				(width 0.1)
				(type default)
			)
			(layer "F.Fab")
		)
		(fp_line
			(start -0.12065 -0.305054)
			(end -0.12065 -0.2794)
			(stroke
				(width 0.1)
				(type default)
			)
			(layer "F.Fab")
		)
		(pad "1" smd circle
			(at -0.40005 0 270)
			(size 0 0)
			(layers "F.Cu" "F.Mask" "F.Paste")
			(net "PVDDCR_CPU1_P1_PVCC")
		)
		(pad "2" smd circle
			(at 0.40005 0 270)
			(size 0 0)
			(layers "F.Cu" "F.Mask" "F.Paste")
			(net "GND")
		)
	)
	(footprint ""
		(layer "F.Cu")
		(at 32.347662 -429.790098 -90)
		(property "Reference" "R3269"
			(at 0 0 270)
			(layer "F.SilkS")
			(hide yes)
			(effects
				(font
					(size 1.27 1.27)
				)
			)
		)
		(property "Value" ""
			(at 0 0 270)
			(layer "F.Fab")
			(effects
				(font
					(size 1.27 1.27)
				)
			)
		)
		(duplicate_pad_numbers_are_jumpers no)
		(fp_line
			(start -0.7874 0.4064)
			(end -0.7874 -0.4064)
			(stroke
				(width 0.1524)
				(type default)
			)
			(layer "F.SilkS")
		)
		(fp_line
			(start 0.7874 0.4064)
			(end -0.7874 0.4064)
			(stroke
				(width 0.1524)
				(type default)
			)
			(layer "F.SilkS")
		)
		(fp_line
			(start -0.7874 -0.4064)
			(end 0.7874 -0.4064)
			(stroke
				(width 0.1524)
				(type default)
			)
			(layer "F.SilkS")
		)
		(fp_line
			(start 0.7874 -0.4064)
			(end 0.7874 0.4064)
			(stroke
				(width 0.1524)
				(type default)
			)
			(layer "F.SilkS")
		)
		(fp_line
			(start -0.67945 0.3048)
			(end -0.67945 -0.305054)
			(stroke
				(width 0.1)
				(type default)
			)
			(layer "F.Fab")
		)
		(fp_line
			(start -0.12065 0.3048)
			(end -0.67945 0.3048)
			(stroke
				(width 0.1)
				(type default)
			)
			(layer "F.Fab")
		)
		(fp_line
			(start 0.120396 0.3048)
			(end 0.120396 0.2794)
			(stroke
				(width 0.1)
				(type default)
			)
			(layer "F.Fab")
		)
		(fp_line
			(start 0.67945 0.3048)
			(end 0.120396 0.3048)
			(stroke
				(width 0.1)
				(type default)
			)
			(layer "F.Fab")
		)
		(fp_line
			(start -0.12065 0.2794)
			(end -0.12065 0.3048)
			(stroke
				(width 0.1)
				(type default)
			)
			(layer "F.Fab")
		)
		(fp_line
			(start 0.120396 0.2794)
			(end -0.12065 0.2794)
			(stroke
				(width 0.1)
				(type default)
			)
			(layer "F.Fab")
		)
		(fp_line
			(start -0.12065 -0.2794)
			(end 0.12065 -0.2794)
			(stroke
				(width 0.1)
				(type default)
			)
			(layer "F.Fab")
		)
		(fp_line
			(start 0.12065 -0.2794)
			(end 0.12065 -0.3048)
			(stroke
				(width 0.1)
				(type default)
			)
			(layer "F.Fab")
		)
		(fp_line
			(start 0.12065 -0.3048)
			(end 0.67945 -0.3048)
			(stroke
				(width 0.1)
				(type default)
			)
			(layer "F.Fab")
		)
		(fp_line
			(start 0.67945 -0.3048)
			(end 0.67945 0.3048)
			(stroke
				(width 0.1)
				(type default)
			)
			(layer "F.Fab")
		)
		(fp_line
			(start -0.67945 -0.305054)
			(end -0.12065 -0.305054)
			(stroke
				(width 0.1)
				(type default)
			)
			(layer "F.Fab")
		)
		(fp_line
			(start -0.12065 -0.305054)
			(end -0.12065 -0.2794)
			(stroke
				(width 0.1)
				(type default)
			)
			(layer "F.Fab")
		)
		(pad "1" smd circle
			(at -0.40005 0 270)
			(size 0 0)
			(layers "F.Cu" "F.Mask" "F.Paste")
			(net "P3V3_AUX")
		)
		(pad "2" smd circle
			(at 0.40005 0 270)
			(size 0 0)
			(layers "F.Cu" "F.Mask" "F.Paste")
			(net "FM_P2E_FGB")
		)
	)
	(footprint ""
		(layer "F.Cu")
		(at 77.128878 -23.308818 180)
		(property "Reference" "PC2098"
			(at 0 0 180)
			(layer "F.SilkS")
			(hide yes)
			(effects
				(font
					(size 1.27 1.27)
				)
			)
		)
		(property "Value" ""
			(at 0 0 180)
			(layer "F.Fab")
			(effects
				(font
					(size 1.27 1.27)
				)
			)
		)
		(duplicate_pad_numbers_are_jumpers no)
		(fp_line
			(start 0.7874 0.4064)
			(end -0.7874 0.4064)
			(stroke
				(width 0.1524)
				(type default)
			)
			(layer "F.SilkS")
		)
		(fp_line
			(start 0.7874 -0.4064)
			(end 0.7874 0.4064)
			(stroke
				(width 0.1524)
				(type default)
			)
			(layer "F.SilkS")
		)
		(fp_line
			(start -0.7874 0.4064)
			(end -0.7874 -0.4064)
			(stroke
				(width 0.1524)
				(type default)
			)
			(layer "F.SilkS")
		)
		(fp_line
			(start -0.7874 -0.4064)
			(end 0.7874 -0.4064)
			(stroke
				(width 0.1524)
				(type default)
			)
			(layer "F.SilkS")
		)
		(fp_line
			(start 0.67945 0.3048)
			(end 0.120396 0.3048)
			(stroke
				(width 0.1)
				(type default)
			)
			(layer "F.Fab")
		)
		(fp_line
			(start 0.67945 -0.3048)
			(end 0.67945 0.3048)
			(stroke
				(width 0.1)
				(type default)
			)
			(layer "F.Fab")
		)
		(fp_line
			(start 0.12065 -0.2794)
			(end 0.12065 -0.3048)
			(stroke
				(width 0.1)
				(type default)
			)
			(layer "F.Fab")
		)
		(fp_line
			(start 0.12065 -0.3048)
			(end 0.67945 -0.3048)
			(stroke
				(width 0.1)
				(type default)
			)
			(layer "F.Fab")
		)
		(fp_line
			(start 0.120396 0.3048)
			(end 0.120396 0.2794)
			(stroke
				(width 0.1)
				(type default)
			)
			(layer "F.Fab")
		)
		(fp_line
			(start 0.120396 0.2794)
			(end -0.12065 0.2794)
			(stroke
				(width 0.1)
				(type default)
			)
			(layer "F.Fab")
		)
		(fp_line
			(start -0.12065 0.3048)
			(end -0.67945 0.3048)
			(stroke
				(width 0.1)
				(type default)
			)
			(layer "F.Fab")
		)
		(fp_line
			(start -0.12065 0.2794)
			(end -0.12065 0.3048)
			(stroke
				(width 0.1)
				(type default)
			)
			(layer "F.Fab")
		)
		(fp_line
			(start -0.12065 -0.2794)
			(end 0.12065 -0.2794)
			(stroke
				(width 0.1)
				(type default)
			)
			(layer "F.Fab")
		)
		(fp_line
			(start -0.12065 -0.305054)
			(end -0.12065 -0.2794)
			(stroke
				(width 0.1)
				(type default)
			)
			(layer "F.Fab")
		)
		(fp_line
			(start -0.67945 0.3048)
			(end -0.67945 -0.305054)
			(stroke
				(width 0.1)
				(type default)
			)
			(layer "F.Fab")
		)
		(fp_line
			(start -0.67945 -0.305054)
			(end -0.12065 -0.305054)
			(stroke
				(width 0.1)
				(type default)
			)
			(layer "F.Fab")
		)
		(pad "1" smd circle
			(at -0.40005 0 180)
			(size 0 0)
			(layers "F.Cu" "F.Mask" "F.Paste")
			(net "P12V_OCP_VCC_2")
		)
		(pad "2" smd circle
			(at 0.40005 0 180)
			(size 0 0)
			(layers "F.Cu" "F.Mask" "F.Paste")
			(net "GND")
		)
	)
)
